(kicad_pcb
	(version 20260206)
	(generator "pcbnew")
	(generator_version "10.0")
	(general
		(thickness 1.6)
		(legacy_teardrops no)
	)
	(paper "A4")
	(title_block
		(title "v1-pdb — T6M_PDB_D_0927_0900.brd")
		(comment 1 "Open CloudServer (Microsoft) / footprints 142-146 of 321")
	)
	(layers
		(0 "F.Cu" signal "TOP")
		(4 "In1.Cu" signal "GND")
		(6 "In2.Cu" signal "IN1")
		(8 "In3.Cu" signal "VCC")
		(10 "In4.Cu" signal "VCC1")
		(12 "In5.Cu" signal "IN2")
		(14 "In6.Cu" signal "GND1")
		(2 "B.Cu" signal "BOTTOM")
		(9 "F.Adhes" user "F.Adhesive")
		(11 "B.Adhes" user "B.Adhesive")
		(13 "F.Paste" user "Package Geometry/Pastemask Top")
		(15 "B.Paste" user "Package Geometry/Pastemask Bottom")
		(5 "F.SilkS" user "Ref Des/Silkscreen Top")
		(7 "B.SilkS" user "Ref Des/Silkscreen Bottom")
		(1 "F.Mask" user "Board Geometry/Soldermask Top")
		(3 "B.Mask" user "Board Geometry/Soldermask Bottom")
		(17 "Dwgs.User" user "User.Drawings")
		(19 "Cmts.User" user "User.Comments")
		(21 "Eco1.User" user "User.Eco1")
		(23 "Eco2.User" user "User.Eco2")
		(25 "Edge.Cuts" user "Board Geometry/Outline")
		(27 "Margin" user)
		(31 "F.CrtYd" user "Package Geometry/Place Bound Top")
		(29 "B.CrtYd" user "Package Geometry/Place Bound Bottom")
		(35 "F.Fab" user "Ref Des/Assembly Top")
		(33 "B.Fab" user "Ref Des/Assembly Bottom")
	)
	(footprint ""
		(layer "F.Cu")
		(at 4.82473 -409.699968)
		(property "Reference" "J28"
			(at -3.8608 -4.816348 0)
			(unlocked yes)
			(layer "F.SilkS")
			(effects
				(font
					(size 0.7874 0.5842)
					(thickness 0.1524)
				)
				(justify left)
			)
		)
		(property "Value" ""
			(at 0 0 0)
			(layer "F.Fab")
			(effects
				(font
					(size 1.27 1.27)
				)
			)
		)
		(duplicate_pad_numbers_are_jumpers no)
		(fp_line
			(start -3.754882 -3.800094)
			(end 12.644882 -3.800094)
			(stroke
				(width 0.1524)
				(type default)
			)
			(layer "F.SilkS")
		)
		(fp_line
			(start -3.754882 1.2192)
			(end -3.754882 -3.800094)
			(stroke
				(width 0.1524)
				(type default)
			)
			(layer "F.SilkS")
		)
		(fp_line
			(start -3.754882 12.899898)
			(end -3.754882 3.7846)
			(stroke
				(width 0.1524)
				(type default)
			)
			(layer "F.SilkS")
		)
		(fp_line
			(start 12.644882 -3.800094)
			(end 12.644882 1.2192)
			(stroke
				(width 0.1524)
				(type default)
			)
			(layer "F.SilkS")
		)
		(fp_line
			(start 12.644882 3.7846)
			(end 12.644882 12.899898)
			(stroke
				(width 0.1524)
				(type default)
			)
			(layer "F.SilkS")
		)
		(fp_line
			(start 12.644882 12.899898)
			(end -3.754882 12.899898)
			(stroke
				(width 0.1524)
				(type default)
			)
			(layer "F.SilkS")
		)
		(fp_poly
			(pts
				(xy -3.807714 -0.117094) (xy -4.479544 0.218948) (xy -4.479544 -0.453136)
			)
			(stroke
				(width 0)
				(type default)
			)
			(fill yes)
			(layer "F.SilkS")
		)
		(fp_poly
			(pts
				(xy -2.591562 11.176) (xy 1.370838 11.176) (xy 1.370838 9.7282) (xy -2.591562 9.7282)
			)
			(stroke
				(width 0)
				(type default)
			)
			(fill no)
			(layer "B.CrtYd")
		)
		(fp_poly
			(pts
				(xy 7.5184 11.176) (xy 11.4808 11.176) (xy 11.4808 9.7282) (xy 7.5184 9.7282)
			)
			(stroke
				(width 0)
				(type default)
			)
			(fill no)
			(layer "B.CrtYd")
		)
		(fp_poly
			(pts
				(xy 9.627362 -3.256026) (xy 9.627362 -1.808226) (xy 8.357362 -1.808226) (xy 8.357362 0.731774) (xy -0.735838 0.731774)
				(xy -0.735838 -0.741426) (xy 0.534162 -0.741426) (xy 0.534162 -3.256026)
			)
			(stroke
				(width 0)
				(type default)
			)
			(fill no)
			(layer "B.CrtYd")
		)
		(fp_poly
			(pts
				(arc
					(start -2.198116 2.500122)
					(mid -4.661916 2.500122)
					(end -2.198116 2.500122)
				)
			)
			(stroke
				(width 0)
				(type default)
			)
			(fill no)
			(layer "B.CrtYd")
		)
		(fp_poly
			(pts
				(arc
					(start 13.551916 2.500122)
					(mid 11.088116 2.500122)
					(end 13.551916 2.500122)
				)
			)
			(stroke
				(width 0)
				(type default)
			)
			(fill no)
			(layer "B.CrtYd")
		)
		(fp_poly
			(pts
				(arc
					(start 0.5842 6.35)
					(mid -3.1242 6.35)
					(end 0.5842 6.35)
				)
			)
			(stroke
				(width 0)
				(type default)
			)
			(fill no)
			(layer "B.CrtYd")
		)
		(fp_poly
			(pts
				(arc
					(start 12.0142 6.35)
					(mid 8.3058 6.35)
					(end 12.0142 6.35)
				)
			)
			(stroke
				(width 0)
				(type default)
			)
			(fill no)
			(layer "B.CrtYd")
		)
		(fp_poly
			(pts
				(xy -3.754882 12.899898)
				(arc
					(start -3.754882 3.688334)
					(mid -4.662083 2.499901)
					(end -3.754882 1.311656)
				)
				(xy -3.754882 -3.800094) (xy 12.644882 -3.800094)
				(arc
					(start 12.644882 1.311656)
					(mid 13.551838 2.499901)
					(end 12.644882 3.688334)
				)
				(xy 12.644882 12.899898)
			)
			(stroke
				(width 0)
				(type default)
			)
			(fill no)
			(layer "F.CrtYd")
		)
		(fp_line
			(start -3.754882 -3.800094)
			(end 12.644882 -3.800094)
			(stroke
				(width 0.1)
				(type default)
			)
			(layer "F.Fab")
		)
		(fp_line
			(start -3.754882 12.899898)
			(end -3.754882 -3.800094)
			(stroke
				(width 0.1)
				(type default)
			)
			(layer "F.Fab")
		)
		(fp_line
			(start 12.644882 -3.800094)
			(end 12.644882 12.899898)
			(stroke
				(width 0.1)
				(type default)
			)
			(layer "F.Fab")
		)
		(fp_line
			(start 12.644882 12.899898)
			(end -3.754882 12.899898)
			(stroke
				(width 0.1)
				(type default)
			)
			(layer "F.Fab")
		)
		(fp_poly
			(pts
				(xy -4.125214 0) (xy -5.806186 0.840486) (xy -5.806186 -0.840486)
			)
			(stroke
				(width 0)
				(type default)
			)
			(fill yes)
			(layer "F.Fab")
		)
		(fp_text user "2"
			(at -4.136136 -2.597912 0)
			(unlocked yes)
			(layer "F.SilkS")
			(effects
				(font
					(size 0.7874 0.5842)
					(thickness 0.1524)
				)
			)
		)
		(fp_text user "1"
			(at -4.098036 -1.035812 0)
			(unlocked yes)
			(layer "F.SilkS")
			(effects
				(font
					(size 0.7874 0.5842)
					(thickness 0.1524)
				)
			)
		)
		(fp_text user "7"
			(at 13.2334 -0.079248 0)
			(unlocked yes)
			(layer "F.SilkS")
			(effects
				(font
					(size 0.7874 0.5842)
					(thickness 0.1524)
				)
			)
		)
		(fp_text user "8"
			(at 13.2715 -2.593848 0)
			(unlocked yes)
			(layer "F.SilkS")
			(effects
				(font
					(size 0.7874 0.5842)
					(thickness 0.1524)
				)
			)
		)
		(fp_text user "1"
			(at -1.1811 -0.053848 0)
			(unlocked yes)
			(layer "B.SilkS")
			(effects
				(font
					(size 0.7874 0.5842)
					(thickness 0.1524)
				)
				(justify mirror)
			)
		)
		(fp_text user "2"
			(at -0.0635 -2.631948 0)
			(unlocked yes)
			(layer "B.SilkS")
			(effects
				(font
					(size 0.7874 0.5842)
					(thickness 0.1524)
				)
				(justify mirror)
			)
		)
		(fp_text user "7"
			(at 8.8646 0.085852 0)
			(unlocked yes)
			(layer "B.SilkS")
			(effects
				(font
					(size 0.7874 0.5842)
					(thickness 0.1524)
				)
				(justify mirror)
			)
		)
		(fp_text user "8"
			(at 10.1219 -2.479548 0)
			(unlocked yes)
			(layer "B.SilkS")
			(effects
				(font
					(size 0.7874 0.5842)
					(thickness 0.1524)
				)
				(justify mirror)
			)
		)
		(fp_text user "1"
			(at -1.1811 -0.053848 0)
			(unlocked yes)
			(layer "B.Fab")
			(effects
				(font
					(size 0.7874 0.5842)
					(thickness 0.000001)
				)
				(justify mirror)
			)
		)
		(fp_text user "2"
			(at -0.0635 -2.631948 0)
			(unlocked yes)
			(layer "B.Fab")
			(effects
				(font
					(size 0.7874 0.5842)
					(thickness 0.000001)
				)
				(justify mirror)
			)
		)
		(fp_text user "7"
			(at 8.8646 0.085852 0)
			(unlocked yes)
			(layer "B.Fab")
			(effects
				(font
					(size 0.7874 0.5842)
					(thickness 0.000001)
				)
				(justify mirror)
			)
		)
		(fp_text user "8"
			(at 10.1219 -2.479548 0)
			(unlocked yes)
			(layer "B.Fab")
			(effects
				(font
					(size 0.7874 0.5842)
					(thickness 0.000001)
				)
				(justify mirror)
			)
		)
		(fp_text user "2"
			(at -4.4704 -2.581148 0)
			(unlocked yes)
			(layer "F.Fab")
			(effects
				(font
					(size 0.7874 0.5842)
					(thickness 0.000001)
				)
			)
		)
		(fp_text user "1"
			(at -4.4323 -1.019048 0)
			(unlocked yes)
			(layer "F.Fab")
			(effects
				(font
					(size 0.7874 0.5842)
					(thickness 0.000001)
				)
			)
		)
		(fp_text user "7"
			(at 13.2334 -0.079248 0)
			(unlocked yes)
			(layer "F.Fab")
			(effects
				(font
					(size 0.7874 0.5842)
					(thickness 0.000001)
				)
			)
		)
		(fp_text user "8"
			(at 13.2715 -2.593848 0)
			(unlocked yes)
			(layer "F.Fab")
			(effects
				(font
					(size 0.7874 0.5842)
					(thickness 0.000001)
				)
			)
		)
		(pad "" np_thru_hole circle
			(at -1.27 6.35)
			(size 3.2004 3.2004)
			(drill 3.2004)
			(layers "*.Cu" "*.Mask")
			(clearance 0.381)
			(thermal_gap 0.381)
		)
		(pad "" np_thru_hole circle
			(at 10.16 6.35)
			(size 3.2004 3.2004)
			(drill 3.2004)
			(layers "*.Cu" "*.Mask")
			(clearance 0.381)
			(thermal_gap 0.381)
		)
		(pad "1" thru_hole rect
			(at 0 0)
			(size 1.3208 1.3208)
			(drill 0.9144)
			(layers "*.Cu" "*.Mask")
			(remove_unused_layers no)
			(net "LAN2_P1_P")
			(clearance 0.0508)
			(thermal_gap 0.0508)
			(padstack
				(mode front_inner_back)
				(layer "Inner"
					(shape circle)
					(size 1.3208 1.3208)
					(clearance 0.0508)
				)
				(layer "B.Cu"
					(shape rect)
					(size 1.3208 1.3208)
					(clearance 0.0508)
				)
			)
		)
		(pad "2" thru_hole circle
			(at 1.27 -2.54)
			(size 1.3208 1.3208)
			(drill 0.9144)
			(layers "*.Cu" "*.Mask")
			(remove_unused_layers no)
			(net "LAN2_P1_N")
			(clearance 0.0508)
			(thermal_gap 0.0508)
		)
		(pad "3" thru_hole circle
			(at 2.54 0)
			(size 1.3208 1.3208)
			(drill 0.9144)
			(layers "*.Cu" "*.Mask")
			(remove_unused_layers no)
			(net "LAN2_P2_P")
			(clearance 0.0508)
			(thermal_gap 0.0508)
		)
		(pad "4" thru_hole circle
			(at 3.81 -2.54)
			(size 1.3208 1.3208)
			(drill 0.9144)
			(layers "*.Cu" "*.Mask")
			(remove_unused_layers no)
			(net "LAN2_P3_P")
			(clearance 0.0508)
			(thermal_gap 0.0508)
		)
		(pad "5" thru_hole circle
			(at 5.08 0)
			(size 1.3208 1.3208)
			(drill 0.9144)
			(layers "*.Cu" "*.Mask")
			(remove_unused_layers no)
			(net "LAN2_P3_N")
			(clearance 0.0508)
			(thermal_gap 0.0508)
		)
		(pad "6" thru_hole circle
			(at 6.35 -2.54)
			(size 1.3208 1.3208)
			(drill 0.9144)
			(layers "*.Cu" "*.Mask")
			(remove_unused_layers no)
			(net "LAN2_P2_N")
			(clearance 0.0508)
			(thermal_gap 0.0508)
		)
		(pad "7" thru_hole circle
			(at 7.62 0)
			(size 1.3208 1.3208)
			(drill 0.9144)
			(layers "*.Cu" "*.Mask")
			(remove_unused_layers no)
			(net "LAN2_P4_P")
			(clearance 0.0508)
			(thermal_gap 0.0508)
		)
		(pad "8" thru_hole circle
			(at 8.89 -2.54)
			(size 1.3208 1.3208)
			(drill 0.9144)
			(layers "*.Cu" "*.Mask")
			(remove_unused_layers no)
			(net "LAN2_P4_N")
			(clearance 0.0508)
			(thermal_gap 0.0508)
		)
		(pad "9" thru_hole circle
			(at -1.854962 10.459974)
			(size 1.3208 1.3208)
			(drill 0.9144)
			(layers "*.Cu" "*.Mask")
			(remove_unused_layers no)
			(net "N42132933")
			(clearance 0.0508)
			(thermal_gap 0.0508)
		)
		(pad "10" thru_hole circle
			(at 0.635 10.459974)
			(size 1.3208 1.3208)
			(drill 0.9144)
			(layers "*.Cu" "*.Mask")
			(remove_unused_layers no)
			(net "N42132545")
			(clearance 0.0508)
			(thermal_gap 0.0508)
		)
		(pad "11" thru_hole circle
			(at 8.255 10.459974)
			(size 1.3208 1.3208)
			(drill 0.9144)
			(layers "*.Cu" "*.Mask")
			(remove_unused_layers no)
			(net "Net_54")
			(clearance 0.0508)
			(thermal_gap 0.0508)
		)
		(pad "12" thru_hole circle
			(at 10.744962 10.459974)
			(size 1.3208 1.3208)
			(drill 0.9144)
			(layers "*.Cu" "*.Mask")
			(remove_unused_layers no)
			(net "N42132358")
			(clearance 0.0508)
			(thermal_gap 0.0508)
		)
		(pad "G1" thru_hole circle
			(at -3.430016 2.500122)
			(size 2.3622 2.3622)
			(drill 1.6002)
			(layers "*.Cu" "*.Mask")
			(remove_unused_layers no)
			(net "GND")
			(clearance -0.127)
		)
		(pad "G2" thru_hole circle
			(at 12.320016 2.500122)
			(size 2.3622 2.3622)
			(drill 1.6002)
			(layers "*.Cu" "*.Mask")
			(remove_unused_layers no)
			(net "GND")
			(clearance -0.127)
		)
		(zone
			(layers "F.Cu" "B.Cu" "In1.Cu" "In2.Cu" "In3.Cu" "In4.Cu" "In5.Cu" "In6.Cu")
			(hatch none 0.5)
			(connect_pads
				(clearance 0)
			)
			(min_thickness 0.25)
			(keepout
				(tracks not_allowed)
				(vias allowed)
				(pads allowed)
				(copperpour not_allowed)
				(footprints allowed)
			)
			(placement
				(enabled no)
				(sheetname "")
			)
			(fill
				(thermal_gap 0.5)
				(thermal_bridge_width 0.5)
				(island_removal_mode 0)
			)
			(polygon
				(pts
					(arc
						(start 5.56133 -403.349968)
						(mid 1.54813 -403.349968)
						(end 5.56133 -403.349968)
					)
				)
			)
		)
		(zone
			(layers "F.Cu" "B.Cu" "In1.Cu" "In2.Cu" "In3.Cu" "In4.Cu" "In5.Cu" "In6.Cu")
			(hatch none 0.5)
			(connect_pads
				(clearance 0)
			)
			(min_thickness 0.25)
			(keepout
				(tracks not_allowed)
				(vias allowed)
				(pads allowed)
				(copperpour not_allowed)
				(footprints allowed)
			)
			(placement
				(enabled no)
				(sheetname "")
			)
			(fill
				(thermal_gap 0.5)
				(thermal_bridge_width 0.5)
				(island_removal_mode 0)
			)
			(polygon
				(pts
					(arc
						(start 16.99133 -403.349968)
						(mid 12.97813 -403.349968)
						(end 16.99133 -403.349968)
					)
				)
			)
		)
	)
	(footprint ""
		(layer "F.Cu")
		(at 27.33421 -197.033896 -90)
		(property "Reference" "R97"
			(at -1.141222 0.065278 90)
			(unlocked yes)
			(layer "F.SilkS")
			(effects
				(font
					(size 0.7874 0.5842)
					(thickness 0.1524)
				)
				(justify left)
			)
		)
		(property "Value" ""
			(at 0 0 270)
			(layer "F.Fab")
			(effects
				(font
					(size 1.27 1.27)
				)
			)
		)
		(duplicate_pad_numbers_are_jumpers no)
		(fp_line
			(start -0.7874 0.4064)
			(end -0.7874 -0.4064)
			(stroke
				(width 0.1524)
				(type default)
			)
			(layer "F.SilkS")
		)
		(fp_line
			(start 0.7874 0.4064)
			(end -0.7874 0.4064)
			(stroke
				(width 0.1524)
				(type default)
			)
			(layer "F.SilkS")
		)
		(fp_line
			(start -0.7874 -0.4064)
			(end 0.7874 -0.4064)
			(stroke
				(width 0.1524)
				(type default)
			)
			(layer "F.SilkS")
		)
		(fp_line
			(start 0.7874 -0.4064)
			(end 0.7874 0.4064)
			(stroke
				(width 0.1524)
				(type default)
			)
			(layer "F.SilkS")
		)
		(fp_poly
			(pts
				(xy -0.508 0.2794) (xy -0.508 0.2286) (xy -0.635 0.2286) (xy -0.635 -0.254) (xy -0.5334 -0.254)
				(xy -0.5334 -0.2794) (xy 0.5334 -0.2794) (xy 0.5334 -0.254) (xy 0.635 -0.254) (xy 0.635 0.254) (xy 0.5334 0.254)
				(xy 0.5334 0.2794)
			)
			(stroke
				(width 0)
				(type default)
			)
			(fill no)
			(layer "F.CrtYd")
		)
		(pad "1" smd rect
			(at 0.40005 0 270)
			(size 0.4572 0.508)
			(layers "F.Cu" "F.Mask" "F.Paste")
			(net "PSU3_REMOTE_N")
		)
		(pad "2" smd rect
			(at -0.40005 0 270)
			(size 0.4572 0.508)
			(layers "F.Cu" "F.Mask" "F.Paste")
			(net "PSU3_REMOTE_R_N")
		)
	)
	(footprint ""
		(layer "F.Cu")
		(at 70.658736 -193.582544 -90)
		(property "Reference" "C30"
			(at 0.978662 -4.1656 90)
			(unlocked yes)
			(layer "F.SilkS")
			(effects
				(font
					(size 0.7874 0.5842)
					(thickness 0.1524)
				)
				(justify left)
			)
		)
		(property "Value" ""
			(at 0 0 270)
			(layer "F.Fab")
			(effects
				(font
					(size 1.27 1.27)
				)
			)
		)
		(duplicate_pad_numbers_are_jumpers no)
		(fp_line
			(start -0.7874 0.4064)
			(end -0.7874 -0.4064)
			(stroke
				(width 0.1524)
				(type default)
			)
			(layer "F.SilkS")
		)
		(fp_line
			(start 0.7874 0.4064)
			(end -0.7874 0.4064)
			(stroke
				(width 0.1524)
				(type default)
			)
			(layer "F.SilkS")
		)
		(fp_line
			(start 0 0.381)
			(end 0 -0.381)
			(stroke
				(width 0.1524)
				(type default)
			)
			(layer "F.SilkS")
		)
		(fp_line
			(start -0.7874 -0.4064)
			(end 0.7874 -0.4064)
			(stroke
				(width 0.1524)
				(type default)
			)
			(layer "F.SilkS")
		)
		(fp_line
			(start 0.7874 -0.4064)
			(end 0.7874 0.4064)
			(stroke
				(width 0.1524)
				(type default)
			)
			(layer "F.SilkS")
		)
		(fp_poly
			(pts
				(xy -0.5334 0.254) (xy -0.635 0.254) (xy -0.635 0.2286) (xy -0.635 -0.254) (xy -0.5334 -0.254) (xy -0.5334 -0.2794)
				(xy 0.5334 -0.2794) (xy 0.5334 -0.254) (xy 0.635 -0.254) (xy 0.635 0.254) (xy 0.5334 0.254) (xy 0.5334 0.2794)
				(xy -0.508 0.2794) (xy -0.5334 0.2794)
			)
			(stroke
				(width 0)
				(type default)
			)
			(fill no)
			(layer "F.CrtYd")
		)
		(pad "1" smd rect
			(at 0.40005 0 270)
			(size 0.4572 0.508)
			(layers "F.Cu" "F.Mask" "F.Paste")
			(net "P12V")
		)
		(pad "2" smd rect
			(at -0.40005 0 270)
			(size 0.4572 0.508)
			(layers "F.Cu" "F.Mask" "F.Paste")
			(net "GND")
		)
	)
	(footprint ""
		(layer "F.Cu")
		(at 73.512934 -415.478722 -90)
		(property "Reference" "C65"
			(at -3.000502 0.051816 90)
			(unlocked yes)
			(layer "F.SilkS")
			(effects
				(font
					(size 0.7874 0.5842)
					(thickness 0.1524)
				)
				(justify left)
			)
		)
		(property "Value" ""
			(at 0 0 270)
			(layer "F.Fab")
			(effects
				(font
					(size 1.27 1.27)
				)
			)
		)
		(duplicate_pad_numbers_are_jumpers no)
		(fp_line
			(start -0.7874 0.4064)
			(end -0.7874 -0.4064)
			(stroke
				(width 0.1524)
				(type default)
			)
			(layer "F.SilkS")
		)
		(fp_line
			(start 0.7874 0.4064)
			(end -0.7874 0.4064)
			(stroke
				(width 0.1524)
				(type default)
			)
			(layer "F.SilkS")
		)
		(fp_line
			(start 0 0.381)
			(end 0 -0.381)
			(stroke
				(width 0.1524)
				(type default)
			)
			(layer "F.SilkS")
		)
		(fp_line
			(start -0.7874 -0.4064)
			(end 0.7874 -0.4064)
			(stroke
				(width 0.1524)
				(type default)
			)
			(layer "F.SilkS")
		)
		(fp_line
			(start 0.7874 -0.4064)
			(end 0.7874 0.4064)
			(stroke
				(width 0.1524)
				(type default)
			)
			(layer "F.SilkS")
		)
		(fp_poly
			(pts
				(xy -0.5334 0.254) (xy -0.635 0.254) (xy -0.635 0.2286) (xy -0.635 -0.254) (xy -0.5334 -0.254) (xy -0.5334 -0.2794)
				(xy 0.5334 -0.2794) (xy 0.5334 -0.254) (xy 0.635 -0.254) (xy 0.635 0.254) (xy 0.5334 0.254) (xy 0.5334 0.2794)
				(xy -0.508 0.2794) (xy -0.5334 0.2794)
			)
			(stroke
				(width 0)
				(type default)
			)
			(fill no)
			(layer "F.CrtYd")
		)
		(pad "1" smd rect
			(at 0.40005 0 270)
			(size 0.4572 0.508)
			(layers "F.Cu" "F.Mask" "F.Paste")
			(net "P12V")
		)
		(pad "2" smd rect
			(at -0.40005 0 270)
			(size 0.4572 0.508)
			(layers "F.Cu" "F.Mask" "F.Paste")
			(net "GND")
		)
	)
	(footprint ""
		(layer "F.Cu")
		(at 26.226008 -449.713858)
		(property "Reference" "R84"
			(at -3.597402 -0.121666 0)
			(unlocked yes)
			(layer "F.SilkS")
			(effects
				(font
					(size 0.7874 0.5842)
					(thickness 0.1524)
				)
				(justify left)
			)
		)
		(property "Value" ""
			(at 0 0 0)
			(layer "F.Fab")
			(effects
				(font
					(size 1.27 1.27)
				)
			)
		)
		(duplicate_pad_numbers_are_jumpers no)
		(fp_line
			(start -0.7874 -0.4064)
			(end 0.7874 -0.4064)
			(stroke
				(width 0.1524)
				(type default)
			)
			(layer "F.SilkS")
		)
		(fp_line
			(start -0.7874 0.4064)
			(end -0.7874 -0.4064)
			(stroke
				(width 0.1524)
				(type default)
			)
			(layer "F.SilkS")
		)
		(fp_line
			(start 0.7874 -0.4064)
			(end 0.7874 0.4064)
			(stroke
				(width 0.1524)
				(type default)
			)
			(layer "F.SilkS")
		)
		(fp_line
			(start 0.7874 0.4064)
			(end -0.7874 0.4064)
			(stroke
				(width 0.1524)
				(type default)
			)
			(layer "F.SilkS")
		)
		(fp_poly
			(pts
				(xy -0.508 0.2794) (xy -0.508 0.2286) (xy -0.635 0.2286) (xy -0.635 -0.254) (xy -0.5334 -0.254)
				(xy -0.5334 -0.2794) (xy 0.5334 -0.2794) (xy 0.5334 -0.254) (xy 0.635 -0.254) (xy 0.635 0.254) (xy 0.5334 0.254)
				(xy 0.5334 0.2794)
			)
			(stroke
				(width 0)
				(type default)
			)
			(fill no)
			(layer "F.CrtYd")
		)
		(pad "1" smd rect
			(at 0.40005 0)
			(size 0.4572 0.508)
			(layers "F.Cu" "F.Mask" "F.Paste")
			(net "PSU6_RESET")
		)
		(pad "2" smd rect
			(at -0.40005 0)
			(size 0.4572 0.508)
			(layers "F.Cu" "F.Mask" "F.Paste")
			(net "P12V_STBY")
		)
	)
)
